(kicad_pcb
	(version 20260206)
	(generator "pcbnew")
	(generator_version "10.0")
	(general
		(thickness 1.6)
		(legacy_teardrops no)
	)
	(paper "A4")
	(title_block
		(title "12092022_DA0F0TMDCD0_F0T_Management_Board_D_brd_V3_OCP.brd")
		(comment 1 "Grand Teton / footprints 1223-1227 of 1440")
	)
	(layers
		(0 "F.Cu" signal "TOP")
		(4 "In1.Cu" signal "GND")
		(6 "In2.Cu" signal "IN1")
		(8 "In3.Cu" signal "GND1")
		(10 "In4.Cu" signal "IN2")
		(12 "In5.Cu" signal "VCC")
		(14 "In6.Cu" signal "VCC1")
		(16 "In7.Cu" signal "IN3")
		(18 "In8.Cu" signal "GND2")
		(20 "In9.Cu" signal "IN4")
		(22 "In10.Cu" signal "GND3")
		(2 "B.Cu" signal "BOTTOM")
		(9 "F.Adhes" user "F.Adhesive")
		(11 "B.Adhes" user "B.Adhesive")
		(13 "F.Paste" user "Package Geometry/Pastemask Top")
		(15 "B.Paste" user "Package Geometry/Pastemask Bottom")
		(5 "F.SilkS" user "Ref Des/Silkscreen Top")
		(7 "B.SilkS" user "Ref Des/Silkscreen Bottom")
		(1 "F.Mask" user "Board Geometry/Soldermask Top")
		(3 "B.Mask" user "Board Geometry/Soldermask Bottom")
		(17 "Dwgs.User" user "User.Drawings")
		(19 "Cmts.User" user "User.Comments")
		(21 "Eco1.User" user "User.Eco1")
		(23 "Eco2.User" user "User.Eco2")
		(25 "Edge.Cuts" user "Board Geometry/Outline")
		(27 "Margin" user)
		(31 "F.CrtYd" user "Package Geometry/Place Bound Top")
		(29 "B.CrtYd" user "Package Geometry/Place Bound Bottom")
		(35 "F.Fab" user "Ref Des/Assembly Top")
		(33 "B.Fab" user "Ref Des/Assembly Bottom")
	)
	(footprint ""
		(layer "B.Cu")
		(at 26.924 -34.925)
		(property "Reference" "ME1"
			(at 0 0 0)
			(layer "B.SilkS")
			(hide yes)
			(effects
				(font
					(size 1.27 1.27)
				)
				(justify mirror)
			)
		)
		(property "Value" ""
			(at 0 0 0)
			(layer "B.Fab")
			(effects
				(font
					(size 1.27 1.27)
				)
				(justify mirror)
			)
		)
		(duplicate_pad_numbers_are_jumpers no)
	)
	(footprint ""
		(layer "B.Cu")
		(at 41.42994 -92.498926 -90)
		(property "Reference" "U22"
			(at 1.847596 4.09194 0)
			(unlocked yes)
			(layer "B.SilkS")
			(effects
				(font
					(size 0.7874 0.5842)
					(thickness 0.1524)
				)
				(justify left mirror)
			)
		)
		(property "Value" ""
			(at 0 0 90)
			(layer "B.Fab")
			(effects
				(font
					(size 1.27 1.27)
				)
				(justify mirror)
			)
		)
		(duplicate_pad_numbers_are_jumpers no)
		(fp_line
			(start 0.254 2.5908)
			(end 0.254 2.99974)
			(stroke
				(width 0.1524)
				(type default)
			)
			(layer "B.SilkS")
		)
		(fp_line
			(start -1.299972 2.29997)
			(end -1.299972 2.032)
			(stroke
				(width 0.1524)
				(type default)
			)
			(layer "B.SilkS")
		)
		(fp_line
			(start -0.5334 2.29997)
			(end -1.299972 2.29997)
			(stroke
				(width 0.1524)
				(type default)
			)
			(layer "B.SilkS")
		)
		(fp_line
			(start 1.299972 2.29997)
			(end 0.5334 2.29997)
			(stroke
				(width 0.1524)
				(type default)
			)
			(layer "B.SilkS")
		)
		(fp_line
			(start 1.299972 2.032)
			(end 1.299972 2.29997)
			(stroke
				(width 0.1524)
				(type default)
			)
			(layer "B.SilkS")
		)
		(fp_line
			(start 1.299972 2.032)
			(end 1.299972 2.29997)
			(stroke
				(width 0.1524)
				(type default)
			)
			(layer "B.SilkS")
		)
		(fp_line
			(start -1.6002 0.254)
			(end -2.1082 0.254)
			(stroke
				(width 0.1524)
				(type default)
			)
			(layer "B.SilkS")
		)
		(fp_line
			(start 1.6002 -0.254)
			(end 2.1082 -0.254)
			(stroke
				(width 0.1524)
				(type default)
			)
			(layer "B.SilkS")
		)
		(fp_line
			(start -1.299972 -2.032)
			(end -1.299972 -2.29997)
			(stroke
				(width 0.1524)
				(type default)
			)
			(layer "B.SilkS")
		)
		(fp_line
			(start -1.299972 -2.29997)
			(end -0.5334 -2.29997)
			(stroke
				(width 0.1524)
				(type default)
			)
			(layer "B.SilkS")
		)
		(fp_line
			(start 0.5334 -2.29997)
			(end 1.299972 -2.29997)
			(stroke
				(width 0.1524)
				(type default)
			)
			(layer "B.SilkS")
		)
		(fp_line
			(start 1.299972 -2.29997)
			(end 1.299972 -2.032)
			(stroke
				(width 0.1524)
				(type default)
			)
			(layer "B.SilkS")
		)
		(fp_line
			(start -0.254 -2.5908)
			(end -0.254 -3.12166)
			(stroke
				(width 0.1524)
				(type default)
			)
			(layer "B.SilkS")
		)
		(fp_poly
			(pts
				(xy 0.249936 -2.516886) (xy 0.55245 -3.121914) (xy -0.052578 -3.121914)
			)
			(stroke
				(width 0)
				(type default)
			)
			(fill yes)
			(layer "B.SilkS")
		)
		(fp_line
			(start 0.254 2.5908)
			(end 0.254 3.6068)
			(stroke
				(width 0.1)
				(type default)
			)
			(layer "B.Fab")
		)
		(fp_line
			(start -1.299972 2.29997)
			(end -1.299972 -2.29997)
			(stroke
				(width 0.1)
				(type default)
			)
			(layer "B.Fab")
		)
		(fp_line
			(start 1.299972 2.29997)
			(end -1.299972 2.29997)
			(stroke
				(width 0.1)
				(type default)
			)
			(layer "B.Fab")
		)
		(fp_line
			(start -1.6002 0.254)
			(end -2.1082 0.254)
			(stroke
				(width 0.1)
				(type default)
			)
			(layer "B.Fab")
		)
		(fp_line
			(start 1.6002 -0.254)
			(end 2.1082 -0.254)
			(stroke
				(width 0.1)
				(type default)
			)
			(layer "B.Fab")
		)
		(fp_line
			(start -1.299972 -2.29997)
			(end 1.299972 -2.29997)
			(stroke
				(width 0.1)
				(type default)
			)
			(layer "B.Fab")
		)
		(fp_line
			(start 1.299972 -2.29997)
			(end 1.299972 2.29997)
			(stroke
				(width 0.1)
				(type default)
			)
			(layer "B.Fab")
		)
		(fp_line
			(start -0.254 -2.5908)
			(end -0.254 -3.6068)
			(stroke
				(width 0.1)
				(type default)
			)
			(layer "B.Fab")
		)
		(fp_poly
			(pts
				(xy 0.249936 -2.516886) (xy 0.55245 -3.121914) (xy -0.052578 -3.121914)
			)
			(stroke
				(width 0)
				(type default)
			)
			(fill yes)
			(layer "B.Fab")
		)
		(fp_text user "9"
			(at 2.0574 1.82245 270)
			(unlocked yes)
			(layer "B.SilkS")
			(effects
				(font
					(size 0.635 0.4064)
					(thickness 0.1524)
				)
				(justify left mirror)
			)
		)
		(fp_text user "12"
			(at -1.608074 1.52019 270)
			(unlocked yes)
			(layer "B.SilkS")
			(effects
				(font
					(size 0.635 0.4064)
					(thickness 0.1524)
				)
				(justify left mirror)
			)
		)
		(fp_text user "2"
			(at 2.032 -1.86055 270)
			(unlocked yes)
			(layer "B.SilkS")
			(effects
				(font
					(size 0.635 0.4064)
					(thickness 0.1524)
				)
				(justify left mirror)
			)
		)
		(fp_text user "19"
			(at -2.370074 -2.03581 270)
			(unlocked yes)
			(layer "B.SilkS")
			(effects
				(font
					(size 0.635 0.4064)
					(thickness 0.1524)
				)
				(justify left mirror)
			)
		)
		(fp_text user "9"
			(at 2.0574 1.82245 270)
			(unlocked yes)
			(layer "B.Fab")
			(effects
				(font
					(size 0.635 0.4064)
					(thickness 0.1524)
				)
				(justify left mirror)
			)
		)
		(fp_text user "12"
			(at -1.524 1.77165 270)
			(unlocked yes)
			(layer "B.Fab")
			(effects
				(font
					(size 0.635 0.4064)
					(thickness 0.1524)
				)
				(justify left mirror)
			)
		)
		(fp_text user "19"
			(at -1.4986 -1.86055 270)
			(unlocked yes)
			(layer "B.Fab")
			(effects
				(font
					(size 0.635 0.4064)
					(thickness 0.1524)
				)
				(justify left mirror)
			)
		)
		(fp_text user "2"
			(at 2.032 -1.86055 270)
			(unlocked yes)
			(layer "B.Fab")
			(effects
				(font
					(size 0.635 0.4064)
					(thickness 0.1524)
				)
				(justify left mirror)
			)
		)
		(pad "1" smd rect
			(at 0.249936 -2.100072 90)
			(size 0.2794 0.6604)
			(layers "B.Cu" "B.Mask" "B.Paste")
			(net "P3V3_AUX")
		)
		(pad "2" smd rect
			(at 1.100074 -1.75006 180)
			(size 0.2794 0.6604)
			(layers "B.Cu" "B.Mask" "B.Paste")
			(net "USB3_MUX_PD")
		)
		(pad "3" smd rect
			(at 1.100074 -1.249934 180)
			(size 0.2794 0.6604)
			(layers "B.Cu" "B.Mask" "B.Paste")
			(net "USB3_01_MUX_FB_TXP")
		)
		(pad "4" smd rect
			(at 1.100074 -0.750062 180)
			(size 0.2794 0.6604)
			(layers "B.Cu" "B.Mask" "B.Paste")
			(net "USB3_01_MUX_FB_TXN")
		)
		(pad "5" smd rect
			(at 1.100074 -0.249936 180)
			(size 0.2794 0.6604)
			(layers "B.Cu" "B.Mask" "B.Paste")
			(net "GND")
		)
		(pad "6" smd rect
			(at 1.100074 0.249936 180)
			(size 0.2794 0.6604)
			(layers "B.Cu" "B.Mask" "B.Paste")
			(net "P3V3_AUX")
		)
		(pad "7" smd rect
			(at 1.100074 0.750062 180)
			(size 0.2794 0.6604)
			(layers "B.Cu" "B.Mask" "B.Paste")
			(net "USB3_01_MUX_FB_RXP")
		)
		(pad "8" smd rect
			(at 1.100074 1.249934 180)
			(size 0.2794 0.6604)
			(layers "B.Cu" "B.Mask" "B.Paste")
			(net "USB3_01_MUX_FB_RXN")
		)
		(pad "9" smd rect
			(at 1.100074 1.75006 180)
			(size 0.2794 0.6604)
			(layers "B.Cu" "B.Mask" "B.Paste")
			(net "DEBUG_PORT_PRSNT")
		)
		(pad "10" smd rect
			(at 0.249936 2.100072 90)
			(size 0.2794 0.6604)
			(layers "B.Cu" "B.Mask" "B.Paste")
			(net "P3V3_AUX")
		)
		(pad "11" smd rect
			(at -0.249936 2.100072 90)
			(size 0.2794 0.6604)
			(layers "B.Cu" "B.Mask" "B.Paste")
			(net "GND")
		)
		(pad "12" smd rect
			(at -1.100074 1.75006 180)
			(size 0.2794 0.6604)
			(layers "B.Cu" "B.Mask" "B.Paste")
			(net "SMB_DEBUG_AUX_LVC3_USB_R2_SCL")
		)
		(pad "13" smd rect
			(at -1.100074 1.249934 180)
			(size 0.2794 0.6604)
			(layers "B.Cu" "B.Mask" "B.Paste")
			(net "SMB_DEBUG_AUX_LVC3_USB_R2_SDA")
		)
		(pad "14" smd rect
			(at -1.100074 0.750062 180)
			(size 0.2794 0.6604)
			(layers "B.Cu" "B.Mask" "B.Paste")
			(net "DEBUG_PORT_UART_TX")
		)
		(pad "15" smd rect
			(at -1.100074 0.249936 180)
			(size 0.2794 0.6604)
			(layers "B.Cu" "B.Mask" "B.Paste")
			(net "DEBUG_PORT_UART_RX")
		)
		(pad "16" smd rect
			(at -1.100074 -0.249936 180)
			(size 0.2794 0.6604)
			(layers "B.Cu" "B.Mask" "B.Paste")
			(net "USB3_FPNL_RXN")
		)
		(pad "17" smd rect
			(at -1.100074 -0.750062 180)
			(size 0.2794 0.6604)
			(layers "B.Cu" "B.Mask" "B.Paste")
			(net "USB3_FPNL_RXP")
		)
		(pad "18" smd rect
			(at -1.100074 -1.249934 180)
			(size 0.2794 0.6604)
			(layers "B.Cu" "B.Mask" "B.Paste")
			(net "USB3_01_TXN_C")
		)
		(pad "19" smd rect
			(at -1.100074 -1.75006 180)
			(size 0.2794 0.6604)
			(layers "B.Cu" "B.Mask" "B.Paste")
			(net "USB3_01_TXP_C")
		)
		(pad "20" smd rect
			(at -0.249936 -2.100072 90)
			(size 0.2794 0.6604)
			(layers "B.Cu" "B.Mask" "B.Paste")
			(net "GND")
		)
		(pad "TH" smd rect
			(at 0 0 90)
			(size 0.9144 2.921)
			(layers "B.Cu" "B.Mask" "B.Paste")
			(net "Net_321")
		)
		(zone
			(layer "B.Cu")
			(hatch none 0.5)
			(connect_pads
				(clearance 0)
			)
			(min_thickness 0.25)
			(keepout
				(tracks not_allowed)
				(vias allowed)
				(pads allowed)
				(copperpour not_allowed)
				(footprints allowed)
			)
			(placement
				(enabled no)
				(sheetname "")
			)
			(fill
				(thermal_gap 0.5)
				(thermal_bridge_width 0.5)
				(island_removal_mode 0)
			)
			(polygon
				(pts
					(xy 43.13174 -92.473526) (xy 42.95394 -92.473526) (xy 42.95394 -91.990926) (xy 39.90594 -91.990926)
					(xy 39.90594 -93.006926) (xy 42.95394 -93.006926) (xy 42.95394 -92.498926) (xy 43.13174 -92.498926)
					(xy 43.13174 -93.210126) (xy 39.72814 -93.210126) (xy 39.72814 -91.787726) (xy 43.13174 -91.787726)
				)
			)
		)
	)
	(footprint ""
		(layer "B.Cu")
		(at 51.682904 -47.617126 -90)
		(property "Reference" "C122"
			(at 0 0 90)
			(layer "B.SilkS")
			(hide yes)
			(effects
				(font
					(size 1.27 1.27)
				)
				(justify mirror)
			)
		)
		(property "Value" ""
			(at 0 0 90)
			(layer "B.Fab")
			(effects
				(font
					(size 1.27 1.27)
				)
				(justify mirror)
			)
		)
		(duplicate_pad_numbers_are_jumpers no)
		(fp_line
			(start -0.7874 0.4064)
			(end 0.7874 0.4064)
			(stroke
				(width 0.1524)
				(type default)
			)
			(layer "B.SilkS")
		)
		(fp_line
			(start 0.7874 0.4064)
			(end 0.7874 -0.4064)
			(stroke
				(width 0.1524)
				(type default)
			)
			(layer "B.SilkS")
		)
		(fp_line
			(start -0.7874 -0.4064)
			(end -0.7874 0.4064)
			(stroke
				(width 0.1524)
				(type default)
			)
			(layer "B.SilkS")
		)
		(fp_line
			(start 0.7874 -0.4064)
			(end -0.7874 -0.4064)
			(stroke
				(width 0.1524)
				(type default)
			)
			(layer "B.SilkS")
		)
		(fp_line
			(start -0.67945 0.3048)
			(end -0.120396 0.3048)
			(stroke
				(width 0.1)
				(type default)
			)
			(layer "B.Fab")
		)
		(fp_line
			(start -0.120396 0.3048)
			(end -0.120396 0.2794)
			(stroke
				(width 0.1)
				(type default)
			)
			(layer "B.Fab")
		)
		(fp_line
			(start 0.12065 0.3048)
			(end 0.67945 0.3048)
			(stroke
				(width 0.1)
				(type default)
			)
			(layer "B.Fab")
		)
		(fp_line
			(start 0.67945 0.3048)
			(end 0.67945 -0.305054)
			(stroke
				(width 0.1)
				(type default)
			)
			(layer "B.Fab")
		)
		(fp_line
			(start -0.120396 0.2794)
			(end 0.12065 0.2794)
			(stroke
				(width 0.1)
				(type default)
			)
			(layer "B.Fab")
		)
		(fp_line
			(start 0.12065 0.2794)
			(end 0.12065 0.3048)
			(stroke
				(width 0.1)
				(type default)
			)
			(layer "B.Fab")
		)
		(fp_line
			(start -0.12065 -0.2794)
			(end -0.12065 -0.3048)
			(stroke
				(width 0.1)
				(type default)
			)
			(layer "B.Fab")
		)
		(fp_line
			(start 0.12065 -0.2794)
			(end -0.12065 -0.2794)
			(stroke
				(width 0.1)
				(type default)
			)
			(layer "B.Fab")
		)
		(fp_line
			(start -0.67945 -0.3048)
			(end -0.67945 0.3048)
			(stroke
				(width 0.1)
				(type default)
			)
			(layer "B.Fab")
		)
		(fp_line
			(start -0.12065 -0.3048)
			(end -0.67945 -0.3048)
			(stroke
				(width 0.1)
				(type default)
			)
			(layer "B.Fab")
		)
		(fp_line
			(start 0.12065 -0.305054)
			(end 0.12065 -0.2794)
			(stroke
				(width 0.1)
				(type default)
			)
			(layer "B.Fab")
		)
		(fp_line
			(start 0.67945 -0.305054)
			(end 0.12065 -0.305054)
			(stroke
				(width 0.1)
				(type default)
			)
			(layer "B.Fab")
		)
		(pad "1" smd circle
			(at 0.40005 0 90)
			(size 0 0)
			(layers "B.Cu" "B.Mask" "B.Paste")
			(net "P1V2_AUX")
		)
		(pad "2" smd circle
			(at -0.40005 0 90)
			(size 0 0)
			(layers "B.Cu" "B.Mask" "B.Paste")
			(net "GND")
		)
	)
	(footprint ""
		(layer "B.Cu")
		(at 62.59322 -61.985906 -90)
		(property "Reference" "C24"
			(at 0 0 90)
			(layer "B.SilkS")
			(hide yes)
			(effects
				(font
					(size 1.27 1.27)
				)
				(justify mirror)
			)
		)
		(property "Value" ""
			(at 0 0 90)
			(layer "B.Fab")
			(effects
				(font
					(size 1.27 1.27)
				)
				(justify mirror)
			)
		)
		(duplicate_pad_numbers_are_jumpers no)
		(fp_line
			(start -0.541274 0.4064)
			(end 0.477266 0.4064)
			(stroke
				(width 0.1524)
				(type default)
			)
			(layer "B.SilkS")
		)
		(fp_line
			(start 0.7874 0.05842)
			(end 0.7874 -0.4064)
			(stroke
				(width 0.1524)
				(type default)
			)
			(layer "B.SilkS")
		)
		(fp_line
			(start -0.7874 -0.4064)
			(end -0.7874 0.11684)
			(stroke
				(width 0.1524)
				(type default)
			)
			(layer "B.SilkS")
		)
		(fp_line
			(start 0.7874 -0.4064)
			(end -0.7874 -0.4064)
			(stroke
				(width 0.1524)
				(type default)
			)
			(layer "B.SilkS")
		)
		(fp_line
			(start -0.67945 0.3048)
			(end -0.120396 0.3048)
			(stroke
				(width 0.1)
				(type default)
			)
			(layer "B.Fab")
		)
		(fp_line
			(start -0.120396 0.3048)
			(end -0.120396 0.2794)
			(stroke
				(width 0.1)
				(type default)
			)
			(layer "B.Fab")
		)
		(fp_line
			(start 0.12065 0.3048)
			(end 0.67945 0.3048)
			(stroke
				(width 0.1)
				(type default)
			)
			(layer "B.Fab")
		)
		(fp_line
			(start 0.67945 0.3048)
			(end 0.67945 -0.305054)
			(stroke
				(width 0.1)
				(type default)
			)
			(layer "B.Fab")
		)
		(fp_line
			(start -0.120396 0.2794)
			(end 0.12065 0.2794)
			(stroke
				(width 0.1)
				(type default)
			)
			(layer "B.Fab")
		)
		(fp_line
			(start 0.12065 0.2794)
			(end 0.12065 0.3048)
			(stroke
				(width 0.1)
				(type default)
			)
			(layer "B.Fab")
		)
		(fp_line
			(start -0.12065 -0.2794)
			(end -0.12065 -0.3048)
			(stroke
				(width 0.1)
				(type default)
			)
			(layer "B.Fab")
		)
		(fp_line
			(start 0.12065 -0.2794)
			(end -0.12065 -0.2794)
			(stroke
				(width 0.1)
				(type default)
			)
			(layer "B.Fab")
		)
		(fp_line
			(start -0.67945 -0.3048)
			(end -0.67945 0.3048)
			(stroke
				(width 0.1)
				(type default)
			)
			(layer "B.Fab")
		)
		(fp_line
			(start -0.12065 -0.3048)
			(end -0.67945 -0.3048)
			(stroke
				(width 0.1)
				(type default)
			)
			(layer "B.Fab")
		)
		(fp_line
			(start 0.12065 -0.305054)
			(end 0.12065 -0.2794)
			(stroke
				(width 0.1)
				(type default)
			)
			(layer "B.Fab")
		)
		(fp_line
			(start 0.67945 -0.305054)
			(end 0.12065 -0.305054)
			(stroke
				(width 0.1)
				(type default)
			)
			(layer "B.Fab")
		)
		(pad "1" smd circle
			(at 0.40005 0 90)
			(size 0 0)
			(layers "B.Cu" "B.Mask" "B.Paste")
			(net "P2E_PCH_TX_DP")
		)
		(pad "2" smd circle
			(at -0.40005 0 90)
			(size 0 0)
			(layers "B.Cu" "B.Mask" "B.Paste")
			(net "P2E_PCH_TX_C_DP")
		)
	)
	(footprint ""
		(layer "B.Cu")
		(at 59.81954 -30.867604 90)
		(property "Reference" "R93"
			(at 0 0 90)
			(layer "B.SilkS")
			(hide yes)
			(effects
				(font
					(size 1.27 1.27)
				)
				(justify mirror)
			)
		)
		(property "Value" ""
			(at 0 0 90)
			(layer "B.Fab")
			(effects
				(font
					(size 1.27 1.27)
				)
				(justify mirror)
			)
		)
		(duplicate_pad_numbers_are_jumpers no)
		(fp_line
			(start 0.7874 -0.4064)
			(end -0.7874 -0.4064)
			(stroke
				(width 0.1524)
				(type default)
			)
			(layer "B.SilkS")
		)
		(fp_line
			(start -0.7874 -0.4064)
			(end -0.7874 0.4064)
			(stroke
				(width 0.1524)
				(type default)
			)
			(layer "B.SilkS")
		)
		(fp_line
			(start 0.7874 0.4064)
			(end 0.7874 -0.4064)
			(stroke
				(width 0.1524)
				(type default)
			)
			(layer "B.SilkS")
		)
		(fp_line
			(start -0.7874 0.4064)
			(end 0.7874 0.4064)
			(stroke
				(width 0.1524)
				(type default)
			)
			(layer "B.SilkS")
		)
		(fp_line
			(start 0.67945 -0.305054)
			(end 0.12065 -0.305054)
			(stroke
				(width 0.1)
				(type default)
			)
			(layer "B.Fab")
		)
		(fp_line
			(start 0.12065 -0.305054)
			(end 0.12065 -0.2794)
			(stroke
				(width 0.1)
				(type default)
			)
			(layer "B.Fab")
		)
		(fp_line
			(start -0.12065 -0.3048)
			(end -0.67945 -0.3048)
			(stroke
				(width 0.1)
				(type default)
			)
			(layer "B.Fab")
		)
		(fp_line
			(start -0.67945 -0.3048)
			(end -0.67945 0.3048)
			(stroke
				(width 0.1)
				(type default)
			)
			(layer "B.Fab")
		)
		(fp_line
			(start 0.12065 -0.2794)
			(end -0.12065 -0.2794)
			(stroke
				(width 0.1)
				(type default)
			)
			(layer "B.Fab")
		)
		(fp_line
			(start -0.12065 -0.2794)
			(end -0.12065 -0.3048)
			(stroke
				(width 0.1)
				(type default)
			)
			(layer "B.Fab")
		)
		(fp_line
			(start 0.12065 0.2794)
			(end 0.12065 0.3048)
			(stroke
				(width 0.1)
				(type default)
			)
			(layer "B.Fab")
		)
		(fp_line
			(start -0.120396 0.2794)
			(end 0.12065 0.2794)
			(stroke
				(width 0.1)
				(type default)
			)
			(layer "B.Fab")
		)
		(fp_line
			(start 0.67945 0.3048)
			(end 0.67945 -0.305054)
			(stroke
				(width 0.1)
				(type default)
			)
			(layer "B.Fab")
		)
		(fp_line
			(start 0.12065 0.3048)
			(end 0.67945 0.3048)
			(stroke
				(width 0.1)
				(type default)
			)
			(layer "B.Fab")
		)
		(fp_line
			(start -0.120396 0.3048)
			(end -0.120396 0.2794)
			(stroke
				(width 0.1)
				(type default)
			)
			(layer "B.Fab")
		)
		(fp_line
			(start -0.67945 0.3048)
			(end -0.120396 0.3048)
			(stroke
				(width 0.1)
				(type default)
			)
			(layer "B.Fab")
		)
		(pad "1" smd circle
			(at 0.40005 0 270)
			(size 0 0)
			(layers "B.Cu" "B.Mask" "B.Paste")
			(net "SMB_BMC_MM5_R_SDA")
		)
		(pad "2" smd circle
			(at -0.40005 0 270)
			(size 0 0)
			(layers "B.Cu" "B.Mask" "B.Paste")
			(net "SMB_BMC_MM5_SDA")
		)
	)
)
